(kicad_pcb
	(version 20260206)
	(generator "pcbnew")
	(generator_version "10.0")
	(general
		(thickness 1.6)
		(legacy_teardrops no)
	)
	(paper "A4")
	(title_block
		(title "12092022_DA0F0TMDCD0_F0T_Management_Board_D_brd_V3_OCP.brd")
		(comment 1 "Grand Teton / footprints 1285-1290 of 1440")
	)
	(layers
		(0 "F.Cu" signal "TOP")
		(4 "In1.Cu" signal "GND")
		(6 "In2.Cu" signal "IN1")
		(8 "In3.Cu" signal "GND1")
		(10 "In4.Cu" signal "IN2")
		(12 "In5.Cu" signal "VCC")
		(14 "In6.Cu" signal "VCC1")
		(16 "In7.Cu" signal "IN3")
		(18 "In8.Cu" signal "GND2")
		(20 "In9.Cu" signal "IN4")
		(22 "In10.Cu" signal "GND3")
		(2 "B.Cu" signal "BOTTOM")
		(9 "F.Adhes" user "F.Adhesive")
		(11 "B.Adhes" user "B.Adhesive")
		(13 "F.Paste" user "Package Geometry/Pastemask Top")
		(15 "B.Paste" user "Package Geometry/Pastemask Bottom")
		(5 "F.SilkS" user "Ref Des/Silkscreen Top")
		(7 "B.SilkS" user "Ref Des/Silkscreen Bottom")
		(1 "F.Mask" user "Board Geometry/Soldermask Top")
		(3 "B.Mask" user "Board Geometry/Soldermask Bottom")
		(17 "Dwgs.User" user "User.Drawings")
		(19 "Cmts.User" user "User.Comments")
		(21 "Eco1.User" user "User.Eco1")
		(23 "Eco2.User" user "User.Eco2")
		(25 "Edge.Cuts" user "Board Geometry/Outline")
		(27 "Margin" user)
		(31 "F.CrtYd" user "Package Geometry/Place Bound Top")
		(29 "B.CrtYd" user "Package Geometry/Place Bound Bottom")
		(35 "F.Fab" user "Ref Des/Assembly Top")
		(33 "B.Fab" user "Ref Des/Assembly Bottom")
	)
	(footprint ""
		(layer "B.Cu")
		(at 53.424582 -55.13197 -90)
		(property "Reference" "C96"
			(at 0 0 90)
			(layer "B.SilkS")
			(hide yes)
			(effects
				(font
					(size 1.27 1.27)
				)
				(justify mirror)
			)
		)
		(property "Value" ""
			(at 0 0 90)
			(layer "B.Fab")
			(effects
				(font
					(size 1.27 1.27)
				)
				(justify mirror)
			)
		)
		(duplicate_pad_numbers_are_jumpers no)
		(fp_line
			(start -0.7874 0.4064)
			(end 0.7874 0.4064)
			(stroke
				(width 0.1524)
				(type default)
			)
			(layer "B.SilkS")
		)
		(fp_line
			(start 0.7874 0.4064)
			(end 0.7874 -0.4064)
			(stroke
				(width 0.1524)
				(type default)
			)
			(layer "B.SilkS")
		)
		(fp_line
			(start -0.7874 -0.4064)
			(end -0.7874 0.4064)
			(stroke
				(width 0.1524)
				(type default)
			)
			(layer "B.SilkS")
		)
		(fp_line
			(start 0.7874 -0.4064)
			(end -0.7874 -0.4064)
			(stroke
				(width 0.1524)
				(type default)
			)
			(layer "B.SilkS")
		)
		(fp_line
			(start -0.67945 0.3048)
			(end -0.120396 0.3048)
			(stroke
				(width 0.1)
				(type default)
			)
			(layer "B.Fab")
		)
		(fp_line
			(start -0.120396 0.3048)
			(end -0.120396 0.2794)
			(stroke
				(width 0.1)
				(type default)
			)
			(layer "B.Fab")
		)
		(fp_line
			(start 0.12065 0.3048)
			(end 0.67945 0.3048)
			(stroke
				(width 0.1)
				(type default)
			)
			(layer "B.Fab")
		)
		(fp_line
			(start 0.67945 0.3048)
			(end 0.67945 -0.305054)
			(stroke
				(width 0.1)
				(type default)
			)
			(layer "B.Fab")
		)
		(fp_line
			(start -0.120396 0.2794)
			(end 0.12065 0.2794)
			(stroke
				(width 0.1)
				(type default)
			)
			(layer "B.Fab")
		)
		(fp_line
			(start 0.12065 0.2794)
			(end 0.12065 0.3048)
			(stroke
				(width 0.1)
				(type default)
			)
			(layer "B.Fab")
		)
		(fp_line
			(start -0.12065 -0.2794)
			(end -0.12065 -0.3048)
			(stroke
				(width 0.1)
				(type default)
			)
			(layer "B.Fab")
		)
		(fp_line
			(start 0.12065 -0.2794)
			(end -0.12065 -0.2794)
			(stroke
				(width 0.1)
				(type default)
			)
			(layer "B.Fab")
		)
		(fp_line
			(start -0.67945 -0.3048)
			(end -0.67945 0.3048)
			(stroke
				(width 0.1)
				(type default)
			)
			(layer "B.Fab")
		)
		(fp_line
			(start -0.12065 -0.3048)
			(end -0.67945 -0.3048)
			(stroke
				(width 0.1)
				(type default)
			)
			(layer "B.Fab")
		)
		(fp_line
			(start 0.12065 -0.305054)
			(end 0.12065 -0.2794)
			(stroke
				(width 0.1)
				(type default)
			)
			(layer "B.Fab")
		)
		(fp_line
			(start 0.67945 -0.305054)
			(end 0.12065 -0.305054)
			(stroke
				(width 0.1)
				(type default)
			)
			(layer "B.Fab")
		)
		(pad "1" smd circle
			(at 0.40005 0 90)
			(size 0 0)
			(layers "B.Cu" "B.Mask" "B.Paste")
			(net "PGPPA_BMC_AUX")
		)
		(pad "2" smd circle
			(at -0.40005 0 90)
			(size 0 0)
			(layers "B.Cu" "B.Mask" "B.Paste")
			(net "GND")
		)
	)
	(footprint ""
		(layer "B.Cu")
		(at 11.9126 -26.9748)
		(property "Reference" "R741"
			(at 0 0 0)
			(layer "B.SilkS")
			(hide yes)
			(effects
				(font
					(size 1.27 1.27)
				)
				(justify mirror)
			)
		)
		(property "Value" ""
			(at 0 0 0)
			(layer "B.Fab")
			(effects
				(font
					(size 1.27 1.27)
				)
				(justify mirror)
			)
		)
		(duplicate_pad_numbers_are_jumpers no)
		(fp_line
			(start -0.7874 -0.4064)
			(end -0.7874 0.4064)
			(stroke
				(width 0.1524)
				(type default)
			)
			(layer "B.SilkS")
		)
		(fp_line
			(start -0.7874 0.4064)
			(end 0.7874 0.4064)
			(stroke
				(width 0.1524)
				(type default)
			)
			(layer "B.SilkS")
		)
		(fp_line
			(start 0.7874 -0.4064)
			(end -0.7874 -0.4064)
			(stroke
				(width 0.1524)
				(type default)
			)
			(layer "B.SilkS")
		)
		(fp_line
			(start 0.7874 0.4064)
			(end 0.7874 -0.4064)
			(stroke
				(width 0.1524)
				(type default)
			)
			(layer "B.SilkS")
		)
		(fp_line
			(start -0.67945 -0.3048)
			(end -0.67945 0.3048)
			(stroke
				(width 0.1)
				(type default)
			)
			(layer "B.Fab")
		)
		(fp_line
			(start -0.67945 0.3048)
			(end -0.120396 0.3048)
			(stroke
				(width 0.1)
				(type default)
			)
			(layer "B.Fab")
		)
		(fp_line
			(start -0.12065 -0.3048)
			(end -0.67945 -0.3048)
			(stroke
				(width 0.1)
				(type default)
			)
			(layer "B.Fab")
		)
		(fp_line
			(start -0.12065 -0.2794)
			(end -0.12065 -0.3048)
			(stroke
				(width 0.1)
				(type default)
			)
			(layer "B.Fab")
		)
		(fp_line
			(start -0.120396 0.2794)
			(end 0.12065 0.2794)
			(stroke
				(width 0.1)
				(type default)
			)
			(layer "B.Fab")
		)
		(fp_line
			(start -0.120396 0.3048)
			(end -0.120396 0.2794)
			(stroke
				(width 0.1)
				(type default)
			)
			(layer "B.Fab")
		)
		(fp_line
			(start 0.12065 -0.305054)
			(end 0.12065 -0.2794)
			(stroke
				(width 0.1)
				(type default)
			)
			(layer "B.Fab")
		)
		(fp_line
			(start 0.12065 -0.2794)
			(end -0.12065 -0.2794)
			(stroke
				(width 0.1)
				(type default)
			)
			(layer "B.Fab")
		)
		(fp_line
			(start 0.12065 0.2794)
			(end 0.12065 0.3048)
			(stroke
				(width 0.1)
				(type default)
			)
			(layer "B.Fab")
		)
		(fp_line
			(start 0.12065 0.3048)
			(end 0.67945 0.3048)
			(stroke
				(width 0.1)
				(type default)
			)
			(layer "B.Fab")
		)
		(fp_line
			(start 0.67945 -0.305054)
			(end 0.12065 -0.305054)
			(stroke
				(width 0.1)
				(type default)
			)
			(layer "B.Fab")
		)
		(fp_line
			(start 0.67945 0.3048)
			(end 0.67945 -0.305054)
			(stroke
				(width 0.1)
				(type default)
			)
			(layer "B.Fab")
		)
		(pad "1" smd circle
			(at 0.40005 0 180)
			(size 0 0)
			(layers "B.Cu" "B.Mask" "B.Paste")
			(net "P3V3_AUX")
		)
		(pad "2" smd circle
			(at -0.40005 0 180)
			(size 0 0)
			(layers "B.Cu" "B.Mask" "B.Paste")
			(net "UART_BMC_5_RXD_BUF")
		)
	)
	(footprint ""
		(layer "B.Cu")
		(at 19.459448 -92.787216 -90)
		(property "Reference" "C164"
			(at 0 0 90)
			(layer "B.SilkS")
			(hide yes)
			(effects
				(font
					(size 1.27 1.27)
				)
				(justify mirror)
			)
		)
		(property "Value" ""
			(at 0 0 90)
			(layer "B.Fab")
			(effects
				(font
					(size 1.27 1.27)
				)
				(justify mirror)
			)
		)
		(duplicate_pad_numbers_are_jumpers no)
		(fp_line
			(start -0.69215 0.2921)
			(end 0.69215 0.2921)
			(stroke
				(width 0.1524)
				(type default)
			)
			(layer "B.SilkS")
		)
		(fp_line
			(start 0.69215 0.2921)
			(end 0.69215 -0.2921)
			(stroke
				(width 0.1524)
				(type default)
			)
			(layer "B.SilkS")
		)
		(fp_line
			(start -0.69215 -0.2921)
			(end -0.69215 0.2921)
			(stroke
				(width 0.1524)
				(type default)
			)
			(layer "B.SilkS")
		)
		(fp_line
			(start 0.69215 -0.2921)
			(end -0.69215 -0.2921)
			(stroke
				(width 0.1524)
				(type default)
			)
			(layer "B.SilkS")
		)
		(fp_line
			(start -0.51435 0.2794)
			(end 0.51435 0.2794)
			(stroke
				(width 0.1)
				(type default)
			)
			(layer "B.Fab")
		)
		(fp_line
			(start 0.51435 0.2794)
			(end 0.51435 -0.2794)
			(stroke
				(width 0.1)
				(type default)
			)
			(layer "B.Fab")
		)
		(fp_line
			(start -0.51435 -0.2794)
			(end -0.51435 0.2794)
			(stroke
				(width 0.1)
				(type default)
			)
			(layer "B.Fab")
		)
		(fp_line
			(start 0.51435 -0.2794)
			(end -0.51435 -0.2794)
			(stroke
				(width 0.1)
				(type default)
			)
			(layer "B.Fab")
		)
		(pad "1" smd circle
			(at 0.40005 0 90)
			(size 0 0)
			(layers "B.Cu" "B.Mask" "B.Paste")
			(net "VCCIO1")
		)
		(pad "2" smd circle
			(at -0.40005 0 90)
			(size 0 0)
			(layers "B.Cu" "B.Mask" "B.Paste")
			(net "GND")
		)
		(zone
			(layer "B.Cu")
			(hatch none 0.5)
			(connect_pads
				(clearance 0)
			)
			(min_thickness 0.25)
			(keepout
				(tracks not_allowed)
				(vias allowed)
				(pads allowed)
				(copperpour not_allowed)
				(footprints allowed)
			)
			(placement
				(enabled no)
				(sheetname "")
			)
			(fill
				(thermal_gap 0.5)
				(thermal_bridge_width 0.5)
				(island_removal_mode 0)
			)
			(polygon
				(pts
					(xy 19.371818 -92.596716) (xy 19.313652 -92.688156) (xy 19.313652 -92.887546) (xy 19.371818 -92.977716)
					(xy 19.547078 -92.977716) (xy 19.605498 -92.887546) (xy 19.605498 -92.688156) (xy 19.547332 -92.596716)
				)
			)
		)
	)
	(footprint ""
		(layer "B.Cu")
		(at 41.966134 -46.16069)
		(property "Reference" "R144"
			(at 0 0 0)
			(layer "B.SilkS")
			(hide yes)
			(effects
				(font
					(size 1.27 1.27)
				)
				(justify mirror)
			)
		)
		(property "Value" ""
			(at 0 0 0)
			(layer "B.Fab")
			(effects
				(font
					(size 1.27 1.27)
				)
				(justify mirror)
			)
		)
		(duplicate_pad_numbers_are_jumpers no)
		(fp_line
			(start -0.7874 -0.4064)
			(end -0.7874 0.4064)
			(stroke
				(width 0.1524)
				(type default)
			)
			(layer "B.SilkS")
		)
		(fp_line
			(start -0.7874 0.4064)
			(end 0.7874 0.4064)
			(stroke
				(width 0.1524)
				(type default)
			)
			(layer "B.SilkS")
		)
		(fp_line
			(start 0.7874 -0.4064)
			(end -0.7874 -0.4064)
			(stroke
				(width 0.1524)
				(type default)
			)
			(layer "B.SilkS")
		)
		(fp_line
			(start 0.7874 0.4064)
			(end 0.7874 -0.4064)
			(stroke
				(width 0.1524)
				(type default)
			)
			(layer "B.SilkS")
		)
		(fp_line
			(start -0.67945 -0.3048)
			(end -0.67945 0.3048)
			(stroke
				(width 0.1)
				(type default)
			)
			(layer "B.Fab")
		)
		(fp_line
			(start -0.67945 0.3048)
			(end -0.120396 0.3048)
			(stroke
				(width 0.1)
				(type default)
			)
			(layer "B.Fab")
		)
		(fp_line
			(start -0.12065 -0.3048)
			(end -0.67945 -0.3048)
			(stroke
				(width 0.1)
				(type default)
			)
			(layer "B.Fab")
		)
		(fp_line
			(start -0.12065 -0.2794)
			(end -0.12065 -0.3048)
			(stroke
				(width 0.1)
				(type default)
			)
			(layer "B.Fab")
		)
		(fp_line
			(start -0.120396 0.2794)
			(end 0.12065 0.2794)
			(stroke
				(width 0.1)
				(type default)
			)
			(layer "B.Fab")
		)
		(fp_line
			(start -0.120396 0.3048)
			(end -0.120396 0.2794)
			(stroke
				(width 0.1)
				(type default)
			)
			(layer "B.Fab")
		)
		(fp_line
			(start 0.12065 -0.305054)
			(end 0.12065 -0.2794)
			(stroke
				(width 0.1)
				(type default)
			)
			(layer "B.Fab")
		)
		(fp_line
			(start 0.12065 -0.2794)
			(end -0.12065 -0.2794)
			(stroke
				(width 0.1)
				(type default)
			)
			(layer "B.Fab")
		)
		(fp_line
			(start 0.12065 0.2794)
			(end 0.12065 0.3048)
			(stroke
				(width 0.1)
				(type default)
			)
			(layer "B.Fab")
		)
		(fp_line
			(start 0.12065 0.3048)
			(end 0.67945 0.3048)
			(stroke
				(width 0.1)
				(type default)
			)
			(layer "B.Fab")
		)
		(fp_line
			(start 0.67945 -0.305054)
			(end 0.12065 -0.305054)
			(stroke
				(width 0.1)
				(type default)
			)
			(layer "B.Fab")
		)
		(fp_line
			(start 0.67945 0.3048)
			(end 0.67945 -0.305054)
			(stroke
				(width 0.1)
				(type default)
			)
			(layer "B.Fab")
		)
		(pad "1" smd circle
			(at 0.40005 0 180)
			(size 0 0)
			(layers "B.Cu" "B.Mask" "B.Paste")
			(net "SMB_BMC_MM12_R_SDA")
		)
		(pad "2" smd circle
			(at -0.40005 0 180)
			(size 0 0)
			(layers "B.Cu" "B.Mask" "B.Paste")
			(net "SMB_BMC_MM12_SDA")
		)
	)
	(footprint ""
		(layer "B.Cu")
		(at 4.7244 -26.797)
		(property "Reference" "C175"
			(at 0 0 0)
			(layer "B.SilkS")
			(hide yes)
			(effects
				(font
					(size 1.27 1.27)
				)
				(justify mirror)
			)
		)
		(property "Value" ""
			(at 0 0 0)
			(layer "B.Fab")
			(effects
				(font
					(size 1.27 1.27)
				)
				(justify mirror)
			)
		)
		(duplicate_pad_numbers_are_jumpers no)
		(fp_line
			(start -0.7874 -0.4064)
			(end -0.7874 0.4064)
			(stroke
				(width 0.1524)
				(type default)
			)
			(layer "B.SilkS")
		)
		(fp_line
			(start -0.7874 0.4064)
			(end 0.7874 0.4064)
			(stroke
				(width 0.1524)
				(type default)
			)
			(layer "B.SilkS")
		)
		(fp_line
			(start 0.7874 -0.4064)
			(end -0.7874 -0.4064)
			(stroke
				(width 0.1524)
				(type default)
			)
			(layer "B.SilkS")
		)
		(fp_line
			(start 0.7874 0.4064)
			(end 0.7874 -0.4064)
			(stroke
				(width 0.1524)
				(type default)
			)
			(layer "B.SilkS")
		)
		(fp_line
			(start -0.67945 -0.3048)
			(end -0.67945 0.3048)
			(stroke
				(width 0.1)
				(type default)
			)
			(layer "B.Fab")
		)
		(fp_line
			(start -0.67945 0.3048)
			(end -0.120396 0.3048)
			(stroke
				(width 0.1)
				(type default)
			)
			(layer "B.Fab")
		)
		(fp_line
			(start -0.12065 -0.3048)
			(end -0.67945 -0.3048)
			(stroke
				(width 0.1)
				(type default)
			)
			(layer "B.Fab")
		)
		(fp_line
			(start -0.12065 -0.2794)
			(end -0.12065 -0.3048)
			(stroke
				(width 0.1)
				(type default)
			)
			(layer "B.Fab")
		)
		(fp_line
			(start -0.120396 0.2794)
			(end 0.12065 0.2794)
			(stroke
				(width 0.1)
				(type default)
			)
			(layer "B.Fab")
		)
		(fp_line
			(start -0.120396 0.3048)
			(end -0.120396 0.2794)
			(stroke
				(width 0.1)
				(type default)
			)
			(layer "B.Fab")
		)
		(fp_line
			(start 0.12065 -0.305054)
			(end 0.12065 -0.2794)
			(stroke
				(width 0.1)
				(type default)
			)
			(layer "B.Fab")
		)
		(fp_line
			(start 0.12065 -0.2794)
			(end -0.12065 -0.2794)
			(stroke
				(width 0.1)
				(type default)
			)
			(layer "B.Fab")
		)
		(fp_line
			(start 0.12065 0.2794)
			(end 0.12065 0.3048)
			(stroke
				(width 0.1)
				(type default)
			)
			(layer "B.Fab")
		)
		(fp_line
			(start 0.12065 0.3048)
			(end 0.67945 0.3048)
			(stroke
				(width 0.1)
				(type default)
			)
			(layer "B.Fab")
		)
		(fp_line
			(start 0.67945 -0.305054)
			(end 0.12065 -0.305054)
			(stroke
				(width 0.1)
				(type default)
			)
			(layer "B.Fab")
		)
		(fp_line
			(start 0.67945 0.3048)
			(end 0.67945 -0.305054)
			(stroke
				(width 0.1)
				(type default)
			)
			(layer "B.Fab")
		)
		(pad "1" smd circle
			(at 0.40005 0 180)
			(size 0 0)
			(layers "B.Cu" "B.Mask" "B.Paste")
			(net "P3V3_AUX")
		)
		(pad "2" smd circle
			(at -0.40005 0 180)
			(size 0 0)
			(layers "B.Cu" "B.Mask" "B.Paste")
			(net "GND")
		)
	)
	(footprint ""
		(layer "B.Cu")
		(at 20.955 -17.907 -90)
		(property "Reference" "R54"
			(at 0 0 90)
			(layer "B.SilkS")
			(hide yes)
			(effects
				(font
					(size 1.27 1.27)
				)
				(justify mirror)
			)
		)
		(property "Value" ""
			(at 0 0 90)
			(layer "B.Fab")
			(effects
				(font
					(size 1.27 1.27)
				)
				(justify mirror)
			)
		)
		(duplicate_pad_numbers_are_jumpers no)
		(fp_line
			(start -0.7874 0.4064)
			(end 0.7874 0.4064)
			(stroke
				(width 0.1524)
				(type default)
			)
			(layer "B.SilkS")
		)
		(fp_line
			(start 0.7874 0.4064)
			(end 0.7874 -0.4064)
			(stroke
				(width 0.1524)
				(type default)
			)
			(layer "B.SilkS")
		)
		(fp_line
			(start -0.7874 -0.4064)
			(end -0.7874 0.4064)
			(stroke
				(width 0.1524)
				(type default)
			)
			(layer "B.SilkS")
		)
		(fp_line
			(start 0.7874 -0.4064)
			(end -0.7874 -0.4064)
			(stroke
				(width 0.1524)
				(type default)
			)
			(layer "B.SilkS")
		)
		(fp_line
			(start -0.67945 0.3048)
			(end -0.120396 0.3048)
			(stroke
				(width 0.1)
				(type default)
			)
			(layer "B.Fab")
		)
		(fp_line
			(start -0.120396 0.3048)
			(end -0.120396 0.2794)
			(stroke
				(width 0.1)
				(type default)
			)
			(layer "B.Fab")
		)
		(fp_line
			(start 0.12065 0.3048)
			(end 0.67945 0.3048)
			(stroke
				(width 0.1)
				(type default)
			)
			(layer "B.Fab")
		)
		(fp_line
			(start 0.67945 0.3048)
			(end 0.67945 -0.305054)
			(stroke
				(width 0.1)
				(type default)
			)
			(layer "B.Fab")
		)
		(fp_line
			(start -0.120396 0.2794)
			(end 0.12065 0.2794)
			(stroke
				(width 0.1)
				(type default)
			)
			(layer "B.Fab")
		)
		(fp_line
			(start 0.12065 0.2794)
			(end 0.12065 0.3048)
			(stroke
				(width 0.1)
				(type default)
			)
			(layer "B.Fab")
		)
		(fp_line
			(start -0.12065 -0.2794)
			(end -0.12065 -0.3048)
			(stroke
				(width 0.1)
				(type default)
			)
			(layer "B.Fab")
		)
		(fp_line
			(start 0.12065 -0.2794)
			(end -0.12065 -0.2794)
			(stroke
				(width 0.1)
				(type default)
			)
			(layer "B.Fab")
		)
		(fp_line
			(start -0.67945 -0.3048)
			(end -0.67945 0.3048)
			(stroke
				(width 0.1)
				(type default)
			)
			(layer "B.Fab")
		)
		(fp_line
			(start -0.12065 -0.3048)
			(end -0.67945 -0.3048)
			(stroke
				(width 0.1)
				(type default)
			)
			(layer "B.Fab")
		)
		(fp_line
			(start 0.12065 -0.305054)
			(end 0.12065 -0.2794)
			(stroke
				(width 0.1)
				(type default)
			)
			(layer "B.Fab")
		)
		(fp_line
			(start 0.67945 -0.305054)
			(end 0.12065 -0.305054)
			(stroke
				(width 0.1)
				(type default)
			)
			(layer "B.Fab")
		)
		(pad "1" smd circle
			(at 0.40005 0 90)
			(size 0 0)
			(layers "B.Cu" "B.Mask" "B.Paste")
			(net "SMB_BMC_ALERT16_R_N")
		)
		(pad "2" smd circle
			(at -0.40005 0 90)
			(size 0 0)
			(layers "B.Cu" "B.Mask" "B.Paste")
			(net "SMB_BMC_ALERT16_N")
		)
	)
)
